(kicad_pcb
	(version 20241229)
	(generator "pcbnew")
	(generator_version "9.0")
	(general
		(thickness 1.63)
		(legacy_teardrops no)
	)
	(paper "A4")
	(title_block
		(title "CM4 Baseboard")
		(date "2026-01-05")
		(rev "1.1.1")
		(company "Antmicro Ltd")
		(comment 1 "www.antmicro.com")
		(comment 9 "footprints 273-273 of 506")
	)
	(layers
		(0 "F.Cu" signal)
		(4 "In1.Cu" power)
		(6 "In2.Cu" power)
		(8 "In3.Cu" signal)
		(10 "In4.Cu" signal)
		(2 "B.Cu" signal)
		(9 "F.Adhes" user "F.Adhesive")
		(11 "B.Adhes" user "B.Adhesive")
		(13 "F.Paste" user)
		(15 "B.Paste" user)
		(5 "F.SilkS" user "F.Silkscreen")
		(7 "B.SilkS" user "B.Silkscreen")
		(1 "F.Mask" user)
		(3 "B.Mask" user)
		(17 "Dwgs.User" user "User.Drawings")
		(19 "Cmts.User" user "User.Comments")
		(21 "Eco1.User" user "User.Eco1")
		(23 "Eco2.User" user "User.Eco2")
		(25 "Edge.Cuts" user)
		(27 "Margin" user)
		(31 "F.CrtYd" user "F.Courtyard")
		(29 "B.CrtYd" user "B.Courtyard")
		(35 "F.Fab" user)
		(33 "B.Fab" user)
	)
	(footprint "antmicro-footprints:C_0402_1005Metric"
		(layer "F.Cu")
		(at 74.617962 178.2415 180)
		(descr "Capacitor SMD 0402")
		(tags "capacitor SMD 0402")
		(property "Reference" "C810"
			(at -2.42 -1.375 0)
			(layer "F.SilkS")
			(effects
				(font
					(size 0.7 0.7)
					(thickness 0.15)
				)
				(justify right bottom)
			)
		)
		(property "Value" "C_10p_0402"
			(at -1.022927 2.155213 0)
			(layer "F.Fab")
			(effects
				(font
					(size 0.7 0.7)
					(thickness 0.15)
				)
				(justify right bottom)
			)
		)
		(property "Datasheet" "https://www.murata.com/products/productdetail?partno=GCM1555C1H100GA16%23"
			(at 0 0 180)
			(layer "F.Fab")
			(hide yes)
			(effects
				(font
					(size 1.27 1.27)
					(thickness 0.15)
				)
			)
		)
		(property "MPN" "GCM1555C1H100GA16D"
			(at 0 0 180)
			(unlocked yes)
			(layer "F.Fab")
			(hide yes)
			(effects
				(font
					(size 1 1)
					(thickness 0.15)
				)
			)
		)
		(property "Manufacturer" "Murata"
			(at 0 0 180)
			(unlocked yes)
			(layer "F.Fab")
			(hide yes)
			(effects
				(font
					(size 1 1)
					(thickness 0.15)
				)
			)
		)
		(property "License" "Apache-2.0"
			(at 0 0 180)
			(unlocked yes)
			(layer "F.Fab")
			(hide yes)
			(effects
				(font
					(size 1 1)
					(thickness 0.15)
				)
			)
		)
		(property "Author" "Antmicro"
			(at 0 0 180)
			(unlocked yes)
			(layer "F.Fab")
			(hide yes)
			(effects
				(font
					(size 1 1)
					(thickness 0.15)
				)
			)
		)
		(property "Val" "10p"
			(at 0 0 180)
			(unlocked yes)
			(layer "F.Fab")
			(hide yes)
			(effects
				(font
					(size 1 1)
					(thickness 0.15)
				)
			)
		)
		(property "Voltage" "50V"
			(at 0 0 180)
			(unlocked yes)
			(layer "F.Fab")
			(hide yes)
			(effects
				(font
					(size 1 1)
					(thickness 0.15)
				)
			)
		)
		(property "Dielectric" "C0G"
			(at 0 0 180)
			(unlocked yes)
			(layer "F.Fab")
			(hide yes)
			(effects
				(font
					(size 1 1)
					(thickness 0.15)
				)
			)
		)
		(sheetname "/Peripherals/")
		(sheetfile "peripherals.kicad_sch")
		(attr smd)
		(fp_rect
			(start -0.925 -0.47)
			(end 0.925 0.47)
			(stroke
				(width 0.05)
				(type default)
			)
			(fill no)
			(layer "F.CrtYd")
		)
		(fp_line
			(start 0.504 0.248)
			(end -0.494 0.248)
			(stroke
				(width 0.15)
				(type solid)
			)
			(layer "F.Fab")
		)
		(fp_line
			(start 0.504 -0.25)
			(end 0.504 0.248)
			(stroke
				(width 0.15)
				(type solid)
			)
			(layer "F.Fab")
		)
		(fp_line
			(start -0.494 0.248)
			(end -0.494 -0.25)
			(stroke
				(width 0.15)
				(type solid)
			)
			(layer "F.Fab")
		)
		(fp_line
			(start -0.494 -0.25)
			(end 0.504 -0.25)
			(stroke
				(width 0.15)
				(type solid)
			)
			(layer "F.Fab")
		)
		(fp_text user "Author: Antmicro"
			(at -0.939 3.399 180)
			(layer "F.Fab")
			(effects
				(font
					(size 0.7 0.7)
					(thickness 0.15)
				)
				(justify left bottom)
			)
		)
		(fp_text user "${REFERENCE}"
			(at -0.939 4.599 180)
			(layer "F.Fab")
			(effects
				(font
					(size 0.7 0.7)
					(thickness 0.15)
				)
				(justify left bottom)
			)
		)
		(fp_text user "License: Apache-2.0"
			(at -0.939 5.799 180)
			(layer "F.Fab")
			(effects
				(font
					(size 0.7 0.7)
					(thickness 0.15)
				)
				(justify left bottom)
			)
		)
		(pad "1" smd roundrect
			(at -0.48 0 180)
			(size 0.59 0.64)
			(layers "F.Cu" "F.Mask" "F.Paste")
			(roundrect_rratio 0.25)
			(net 3 "GND")
			(pintype "passive")
		)
		(pad "2" smd roundrect
			(at 0.48 0 180)
			(size 0.59 0.64)
			(layers "F.Cu" "F.Mask" "F.Paste")
			(roundrect_rratio 0.25)
			(net 99 "Net-(U801-XTAL2)")
			(pintype "passive")
		)
	)
)
